# S9S_MB_2U (Grand Teton) — schematic netlist excerpt (pin names and nets, part order shuffled) for the footprints in the layout excerpt that follows; sources: Cadence DE-HDL packaged netlist, KiCad conversion of 03242023_DA0F0TMBIJ0_F0T_Motherboard_J_brd_V01_OCP.brd

J19  SCONN288_ADR50017P130CC  SCONN288_ADR50017-P130CC IO  pkg DDR288S_1-1VXB  page 100
  VIN_BULK0  = P12V_S3_AUX_CPU1_NVDIMM
  RFU0  = TP_CHB_CPU1_DIMM1_FRU_0
  VIN_MGMT  = P3V3_AUX
  HSCL  = I3C_SPD_DDRABCD_CPU1_LVC1_SCL_2
  HSDA  = I3C_SPD_DDRABCD_CPU1_LVC1_SDA
  VSS0  = GND
  DQ0_A  = M_B_CPU1_SA_DQ<0>
  VSS1  = GND
  DQ1_A  = M_B_CPU1_SA_DQ<1>
  VSS2  = GND
  DQS0_A_T  = M_B_CPU1_SA_DQS_DP<0>
  DQS0_A_C  = M_B_CPU1_SA_DQS_DN<0>
  VSS3  = GND
  DQ4_A  = M_B_CPU1_SA_DQ<4>
  VSS4  = GND
  DQ5_A  = M_B_CPU1_SA_DQ<5>
  VSS5  = GND
  DQ8_A  = M_B_CPU1_SA_DQ<8>
  VSS6  = GND
  DQ9_A  = M_B_CPU1_SA_DQ<9>
  VSS7  = GND
  DQS1_A_T  = M_B_CPU1_SA_DQS_DP<1>
  DQS1_A_C  = M_B_CPU1_SA_DQS_DN<1>
  VSS8  = GND
  DQ12_A  = M_B_CPU1_SA_DQ<12>
  VSS9  = GND
  DQ13_A  = M_B_CPU1_SA_DQ<13>
  VSS10  = GND
  DQ16_A  = M_B_CPU1_SA_DQ<16>
  VSS11  = GND
  DQ17_A  = M_B_CPU1_SA_DQ<17>
  VSS12  = GND
  DQS2_A_T  = M_B_CPU1_SA_DQS_DP<2>
  DQS2_A_C  = M_B_CPU1_SA_DQS_DN<2>
  VSS13  = GND
  DQ20_A  = M_B_CPU1_SA_DQ<20>
  VSS14  = GND
  DQ21_A  = M_B_CPU1_SA_DQ<21>
  VSS15  = GND
  DQ24_A  = M_B_CPU1_SA_DQ<24>
  VSS16  = GND
  DQ25_A  = M_B_CPU1_SA_DQ<25>
  VSS17  = GND
  DQS3_A_T  = M_B_CPU1_SA_DQS_DP<3>
  DQS3_A_C  = M_B_CPU1_SA_DQS_DN<3>
  VSS18  = GND
  DQ28_A  = M_B_CPU1_SA_DQ<28>
  VSS19  = GND
  DQ29_A  = M_B_CPU1_SA_DQ<29>
  VSS20  = GND
  CB0_A  = M_B_CPU1_SA_CB<0>
  VSS21  = GND
  CB1_A  = M_B_CPU1_SA_CB<1>
  VSS22  = GND
  DQS4_A_T  = M_B_CPU1_SA_DQS_DP<4>
  DQS4_A_C  = M_B_CPU1_SA_DQS_DN<4>
  VSS23  = GND
  CB4_A  = M_B_CPU1_SA_CB<4>
  VSS24  = GND
  CB5_A  = M_B_CPU1_SA_CB<5>
  VSS25  = GND
  ALERT_N  = M_B_CPU1_ALERT_N
  VSS26  = GND
  CS0_A_N  = M_B_CPU1_SA_CS_N<0>
  VSS27  = GND
  CA0_A  = M_B_CPU1_SA_CA<0>
  VSS28  = GND
  CA2_A  = M_B_CPU1_SA_CA<2>
  VSS29  = GND
  CA4_A  = M_B_CPU1_SA_CA<4>
  VSS30  = GND
  CA6_A  = M_B_CPU1_SA_CA<6>
  VSS31  = GND
  PAR_A  = M_B_CPU1_SA_PAR
  VSS32  = GND
  CA0_B  = M_B_CPU1_SB_CA<0>
  VSS33  = GND
  CA2_B  = M_B_CPU1_SB_CA<2>
  VSS34  = GND
  CA4_B  = M_B_CPU1_SB_CA<4>
  VSS35  = GND
  CA6_B  = M_B_CPU1_SB_CA<6>
  VSS36  = GND
  CS0_B_N  = M_B_CPU1_SB_CS_N<0>
  VSS37  = GND
  \lbd||rsp_a_n\  = M_B_CPU1_SA_RSP<0>
  \lbs||rsp_b_n\  = M_B_CPU1_SB_RSP<0>
  VSS38  = GND
  CB4_B  = M_B_CPU1_SB_CB<4>
  VSS39  = GND
  CB5_B  = M_B_CPU1_SB_CB<5>
  VSS40  = GND
  \dqs9_b_t||tdqs9_b_t||dbi4_b_n\  = M_B_CPU1_SB_DQS_DP<9>
  \dqs9_b_c||tdqs9_b_c\  = M_B_CPU1_SB_DQS_DN<9>
  VSS41  = GND
  CB0_B  = M_B_CPU1_SB_CB<0>
  VSS42  = GND
  CB1_B  = M_B_CPU1_SB_CB<1>
  VSS43  = GND
  DQ0_B  = M_B_CPU1_SB_DQ<0>
  VSS44  = GND
  DQ1_B  = M_B_CPU1_SB_DQ<1>
  VSS45  = GND
  DQS0_B_T  = M_B_CPU1_SB_DQS_DP<0>
  DQS0_B_C  = M_B_CPU1_SB_DQS_DN<0>
  VSS46  = GND
  DQ4_B  = M_B_CPU1_SB_DQ<4>
  VSS47  = GND
  DQ5_B  = M_B_CPU1_SB_DQ<5>
  VSS48  = GND
  DQ8_B  = M_B_CPU1_SB_DQ<8>
  VSS49  = GND
  DQ9_B  = M_B_CPU1_SB_DQ<9>
  VSS50  = GND
  DQS1_B_T  = M_B_CPU1_SB_DQS_DP<1>
  DQS1_B_C  = M_B_CPU1_SB_DQS_DN<1>
  VSS51  = GND
  DQ12_B  = M_B_CPU1_SB_DQ<12>
  VSS52  = GND
  DQ13_B  = M_B_CPU1_SB_DQ<13>
  VSS53  = GND
  DQ16_B  = M_B_CPU1_SB_DQ<16>
  VSS54  = GND
  DQ17_B  = M_B_CPU1_SB_DQ<17>
  VSS55  = GND
  DQS2_B_T  = M_B_CPU1_SB_DQS_DP<2>
  DQS2_B_C  = M_B_CPU1_SB_DQS_DN<2>
  VSS56  = GND
  DQ20_B  = M_B_CPU1_SB_DQ<20>
  VSS57  = GND
  DQ21_B  = M_B_CPU1_SB_DQ<21>
  VSS58  = GND
  DQ24_B  = M_B_CPU1_SB_DQ<24>
  VSS59  = GND
  DQ25_B  = M_B_CPU1_SB_DQ<25>
  VSS60  = GND
  DQS3_B_T  = M_B_CPU1_SB_DQS_DP<3>
  DQS3_B_C  = M_B_CPU1_SB_DQS_DN<3>
  VSS61  = GND
  DQ28_B  = M_B_CPU1_SB_DQ<28>
  VSS62  = GND
  DQ29_B  = M_B_CPU1_SB_DQ<29>
  VSS63  = GND
  RFU1  = TP_CHB_CPU1_DIMM1_FRU_1
  VIN_BULK1  = P12V_S3_AUX_CPU1_NVDIMM
  VIN_BULK2  = P12V_S3_AUX_CPU1_NVDIMM
  \pwr_good||fail_n\  = PWRGD_CHB_CPU1_DIMM1
  HSA  = PD_CHB_CPU1_DIMM1_SAA
  RFU2  = TP_CHB_CPU1_DIMM1_FRU_2
  RFU3  = TP_CHB_CPU1_DIMM1_FRU_3
  VSS64  = GND
  DQ2_A  = M_B_CPU1_SA_DQ<2>
  VSS65  = GND
  DQ3_A  = M_B_CPU1_SA_DQ<3>
  VSS66  = GND
  \dqs5_a_c||tdqs5_a_c||dqs5_a_t||tdqs5_a_t\  = M_B_CPU1_SA_DQS_DN<5>
  \dqs5_a_t||tdqs5_a_t\  = M_B_CPU1_SA_DQS_DP<5>
  VSS67  = GND
  DQ6_A  = M_B_CPU1_SA_DQ<6>
  VSS68  = GND
  DQ7_A  = M_B_CPU1_SA_DQ<7>
  VSS69  = GND
  DQ10_A  = M_B_CPU1_SA_DQ<10>
  VSS70  = GND
  DQ11_A  = M_B_CPU1_SA_DQ<11>
  VSS71  = GND
  \dqs6_a_c||tdqs6_a_c||dqs6_a_t||tdqs6_a_t\  = M_B_CPU1_SA_DQS_DN<6>
  \dqs6_a_t||tdqs6_a_t\  = M_B_CPU1_SA_DQS_DP<6>
  VSS72  = GND
  DQ14_A  = M_B_CPU1_SA_DQ<14>
  VSS73  = GND
  DQ15_A  = M_B_CPU1_SA_DQ<15>
  VSS74  = GND
  DQ18_A  = M_B_CPU1_SA_DQ<18>
  VSS75  = GND
  DQ19_A  = M_B_CPU1_SA_DQ<19>
  VSS76  = GND
  \dqs7_a_c||tdqs7_a_c\  = M_B_CPU1_SA_DQS_DN<7>
  \dqs7_a_t||tdqs7_a_t\  = M_B_CPU1_SA_DQS_DP<7>
  VSS77  = GND
  DQ22_A  = M_B_CPU1_SA_DQ<22>
  VSS78  = GND
  DQ23_A  = M_B_CPU1_SA_DQ<23>
  VSS79  = GND
  DQ26_A  = M_B_CPU1_SA_DQ<26>
  VSS80  = GND
  DQ27_A  = M_B_CPU1_SA_DQ<27>
  VSS81  = GND
  \dqs8_a_c||tdqs8_a_c\  = M_B_CPU1_SA_DQS_DN<8>
  \dqs8_a_t||tdqs8_a_t\  = M_B_CPU1_SA_DQS_DP<8>
  VSS82  = GND
  DQ30_A  = M_B_CPU1_SA_DQ<30>
  VSS83  = GND
  DQ31_A  = M_B_CPU1_SA_DQ<31>
  VSS84  = GND
  CB2_A  = M_B_CPU1_SA_CB<2>
  VSS85  = GND
  CB3_A  = M_B_CPU1_SA_CB<3>
  VSS86  = GND
  \dqs9_a_c||tdqs9_a_c\  = M_B_CPU1_SA_DQS_DN<9>
  \dqs9_a_t||tdqs9_a_t\  = M_B_CPU1_SA_DQS_DP<9>
  VSS87  = GND
  CB6_A  = M_B_CPU1_SA_CB<6>
  VSS88  = GND
  CB7_A  = M_B_CPU1_SA_CB<7>
  VSS89  = GND
  RESET_N  = RST_M_AB_CPU1_FPGA_N
  VSS90  = GND
  CS1_A_N  = M_B_CPU1_SA_CS_N<1>
  VSS91  = GND
  CA1_A  = M_B_CPU1_SA_CA<1>
  VSS92  = GND
  CA3_A  = M_B_CPU1_SA_CA<3>
  VSS93  = GND
  CA5_A  = M_B_CPU1_SA_CA<5>
  VSS94  = GND
  CK_T  = M_B_CPU1_CLK_DP<0>
  CK_C  = M_B_CPU1_CLK_DN<0>
  VSS95  = GND
  RFU4  = TP_CHB_CPU1_DIMM1_FRU_4
  CA1_B  = M_B_CPU1_SB_CA<1>
  VSS96  = GND
  CA3_B  = M_B_CPU1_SB_CA<3>
  VSS97  = GND
  CA5_B  = M_B_CPU1_SB_CA<5>
  VSS98  = GND
  PAR_B  = M_B_CPU1_SB_PAR
  VSS99  = GND
  CS1_B_N  = M_B_CPU1_SB_CS_N<1>
  VSS100  = GND
  RFU5  = TP_CHB_CPU1_DIMM1_FRU_5
  RFU6  = TP_CHB_CPU1_DIMM1_FRU_6
  VSS101  = GND
  CB6_B  = M_B_CPU1_SB_CB<6>
  VSS102  = GND
  CB7_B  = M_B_CPU1_SB_CB<7>
  VSS103  = GND
  DQS4_B_C  = M_B_CPU1_SB_DQS_DN<4>
  DQS4_B_T  = M_B_CPU1_SB_DQS_DP<4>
  VSS104  = GND
  CB2_B  = M_B_CPU1_SB_CB<2>
  VSS105  = GND
  CB3_B  = M_B_CPU1_SB_CB<3>
  VSS106  = GND
  DQ2_B  = M_B_CPU1_SB_DQ<2>
  VSS107  = GND
  DQ3_B  = M_B_CPU1_SB_DQ<3>
  VSS108  = GND
  \dqs5_b_c||tdqs5_b_c\  = M_B_CPU1_SB_DQS_DN<5>
  \dqs5_b_t||tdqs5_b_t\  = M_B_CPU1_SB_DQS_DP<5>
  VSS109  = GND
  DQ6_B  = M_B_CPU1_SB_DQ<6>
  VSS110  = GND
  DQ7_B  = M_B_CPU1_SB_DQ<7>
  VSS111  = GND
  DQ10_B  = M_B_CPU1_SB_DQ<10>
  VSS112  = GND
  DQ11_B  = M_B_CPU1_SB_DQ<11>
  VSS113  = GND
  \dqs6_b_c||tdqs6_b_c\  = M_B_CPU1_SB_DQS_DN<6>
  \dqs6_b_t||tdqs6_b_t\  = M_B_CPU1_SB_DQS_DP<6>
  VSS114  = GND
  DQ14_B  = M_B_CPU1_SB_DQ<14>
  VSS115  = GND
  DQ15_B  = M_B_CPU1_SB_DQ<15>
  VSS116  = GND
  DQ18_B  = M_B_CPU1_SB_DQ<18>
  VSS117  = GND
  DQ19_B  = M_B_CPU1_SB_DQ<19>
  VSS118  = GND
  \dqs7_b_c||tdqs7_b_c\  = M_B_CPU1_SB_DQS_DN<7>
  \dqs7_b_t||tdqs7_b_t\  = M_B_CPU1_SB_DQS_DP<7>
  VSS119  = GND
  DQ22_B  = M_B_CPU1_SB_DQ<22>
  VSS120  = GND
  DQ23_B  = M_B_CPU1_SB_DQ<23>
  VSS121  = GND
  DQ26_B  = M_B_CPU1_SB_DQ<26>
  VSS122  = GND
  DQ27_B  = M_B_CPU1_SB_DQ<27>
  VSS123  = GND
  \dqs8_b_c||tdqs8_b_c\  = M_B_CPU1_SB_DQS_DN<8>
  \dqs8_b_t||tdqs8_b_t\  = M_B_CPU1_SB_DQS_DP<8>
  VSS124  = GND
  DQ30_B  = M_B_CPU1_SB_DQ<30>
  VSS125  = GND
  DQ31_B  = M_B_CPU1_SB_DQ<31>
  VSS126  = GND
  G1  = GND
  G2  = GND
  G3  = GND

(kicad_pcb
	(version 20260206)
	(generator "pcbnew")
	(generator_version "10.0")
	(general
		(thickness 1.6)
		(legacy_teardrops no)
	)
	(paper "A4")
	(title_block
		(title "03242023_DA0F0TMBIJ0_F0T_Motherboard_J_brd_V01_OCP.brd")
		(comment 1 "Grand Teton / footprint 2188 of 6105 (J19), pads 229-274 of 291")
	)
	(layers
		(0 "F.Cu" signal "TOP")
		(4 "In1.Cu" signal "GND")
		(6 "In2.Cu" signal "IN1")
		(8 "In3.Cu" signal "GND1")
		(10 "In4.Cu" signal "IN2")
		(12 "In5.Cu" signal "GND2")
		(14 "In6.Cu" signal "IN3")
		(16 "In7.Cu" signal "GND3")
		(18 "In8.Cu" signal "VCC")
		(20 "In9.Cu" signal "VCC1")
		(22 "In10.Cu" signal "GND4")
		(24 "In11.Cu" signal "IN4")
		(26 "In12.Cu" signal "GND5")
		(28 "In13.Cu" signal "IN5")
		(30 "In14.Cu" signal "GND6")
		(32 "In15.Cu" signal "IN6")
		(34 "In16.Cu" signal "GND7")
		(2 "B.Cu" signal "BOTTOM")
		(9 "F.Adhes" user "F.Adhesive")
		(11 "B.Adhes" user "B.Adhesive")
		(13 "F.Paste" user "Package Geometry/Pastemask Top")
		(15 "B.Paste" user "Package Geometry/Pastemask Bottom")
		(5 "F.SilkS" user "Ref Des/Silkscreen Top")
		(7 "B.SilkS" user "Ref Des/Silkscreen Bottom")
		(1 "F.Mask" user "Board Geometry/Soldermask Top")
		(3 "B.Mask" user "Board Geometry/Soldermask Bottom")
		(17 "Dwgs.User" user "User.Drawings")
		(19 "Cmts.User" user "User.Comments")
		(21 "Eco1.User" user "User.Eco1")
		(23 "Eco2.User" user "User.Eco2")
		(25 "Edge.Cuts" user "Board Geometry/Outline")
		(27 "Margin" user)
		(31 "F.CrtYd" user "Package Geometry/Place Bound Top")
		(29 "B.CrtYd" user "Package Geometry/Place Bound Bottom")
		(35 "F.Fab" user "Ref Des/Assembly Top")
		(33 "B.Fab" user "Ref Des/Assembly Bottom")
	)
	(footprint ""
		(layer "F.Cu")
		(at 40.36568 -258.091686)
		(property "Reference" "J19"
			(at -5.21716 -81.970372 0)
			(unlocked yes)
			(layer "F.SilkS")
			(effects
				(font
					(size 0.7874 0.5842)
					(thickness 0.1524)
				)
				(justify left)
			)
		)
		(property "Value" ""
			(at 0 0 0)
			(layer "F.Fab")
			(effects
				(font
					(size 1.27 1.27)
				)
			)
		)
		(duplicate_pad_numbers_are_jumpers no)
		(pad "229" smd rect
			(at 2.050034 13.17498 270)
			(size 0.519938 1.4986)
			(layers "F.Cu" "F.Mask" "F.Paste")
			(net "M_B_CPU1_SB_CS_N<1>")
		)
		(pad "230" smd rect
			(at 2.050034 14.025118 270)
			(size 0.519938 1.4986)
			(layers "F.Cu" "F.Mask" "F.Paste")
			(net "GND")
		)
		(pad "231" smd rect
			(at 2.050034 14.875002 270)
			(size 0.519938 1.4986)
			(layers "F.Cu" "F.Mask" "F.Paste")
			(net "TP_CHB_CPU1_DIMM1_FRU_5")
		)
		(pad "232" smd rect
			(at 2.050034 15.724886 270)
			(size 0.519938 1.4986)
			(layers "F.Cu" "F.Mask" "F.Paste")
			(net "TP_CHB_CPU1_DIMM1_FRU_6")
		)
		(pad "233" smd rect
			(at 2.050034 16.575024 270)
			(size 0.519938 1.4986)
			(layers "F.Cu" "F.Mask" "F.Paste")
			(net "GND")
		)
		(pad "234" smd rect
			(at 2.050034 17.424908 270)
			(size 0.519938 1.4986)
			(layers "F.Cu" "F.Mask" "F.Paste")
			(net "M_B_CPU1_SB_CB<6>")
		)
		(pad "235" smd rect
			(at 2.050034 18.275046 270)
			(size 0.519938 1.4986)
			(layers "F.Cu" "F.Mask" "F.Paste")
			(net "GND")
		)
		(pad "236" smd rect
			(at 2.050034 19.12493 270)
			(size 0.519938 1.4986)
			(layers "F.Cu" "F.Mask" "F.Paste")
			(net "M_B_CPU1_SB_CB<7>")
		)
		(pad "237" smd rect
			(at 2.050034 19.975068 270)
			(size 0.519938 1.4986)
			(layers "F.Cu" "F.Mask" "F.Paste")
			(net "GND")
		)
		(pad "238" smd rect
			(at 2.050034 20.824952 270)
			(size 0.519938 1.4986)
			(layers "F.Cu" "F.Mask" "F.Paste")
			(net "M_B_CPU1_SB_DQS_DN<4>")
		)
		(pad "239" smd rect
			(at 2.050034 21.67509 270)
			(size 0.519938 1.4986)
			(layers "F.Cu" "F.Mask" "F.Paste")
			(net "M_B_CPU1_SB_DQS_DP<4>")
		)
		(pad "240" smd rect
			(at 2.050034 22.524974 270)
			(size 0.519938 1.4986)
			(layers "F.Cu" "F.Mask" "F.Paste")
			(net "GND")
		)
		(pad "241" smd rect
			(at 2.050034 23.375112 270)
			(size 0.519938 1.4986)
			(layers "F.Cu" "F.Mask" "F.Paste")
			(net "M_B_CPU1_SB_CB<2>")
		)
		(pad "242" smd rect
			(at 2.050034 24.224996 270)
			(size 0.519938 1.4986)
			(layers "F.Cu" "F.Mask" "F.Paste")
			(net "GND")
		)
		(pad "243" smd rect
			(at 2.050034 25.07488 270)
			(size 0.519938 1.4986)
			(layers "F.Cu" "F.Mask" "F.Paste")
			(net "M_B_CPU1_SB_CB<3>")
		)
		(pad "244" smd rect
			(at 2.050034 25.925018 270)
			(size 0.519938 1.4986)
			(layers "F.Cu" "F.Mask" "F.Paste")
			(net "GND")
		)
		(pad "245" smd rect
			(at 2.050034 26.774902 270)
			(size 0.519938 1.4986)
			(layers "F.Cu" "F.Mask" "F.Paste")
			(net "M_B_CPU1_SB_DQ<2>")
		)
		(pad "246" smd rect
			(at 2.050034 27.62504 270)
			(size 0.519938 1.4986)
			(layers "F.Cu" "F.Mask" "F.Paste")
			(net "GND")
		)
		(pad "247" smd rect
			(at 2.050034 28.474924 270)
			(size 0.519938 1.4986)
			(layers "F.Cu" "F.Mask" "F.Paste")
			(net "M_B_CPU1_SB_DQ<3>")
		)
		(pad "248" smd rect
			(at 2.050034 29.325062 270)
			(size 0.519938 1.4986)
			(layers "F.Cu" "F.Mask" "F.Paste")
			(net "GND")
		)
		(pad "249" smd rect
			(at 2.050034 30.174946 270)
			(size 0.519938 1.4986)
			(layers "F.Cu" "F.Mask" "F.Paste")
			(net "M_B_CPU1_SB_DQS_DN<5>")
		)
		(pad "250" smd rect
			(at 2.050034 31.025084 270)
			(size 0.519938 1.4986)
			(layers "F.Cu" "F.Mask" "F.Paste")
			(net "M_B_CPU1_SB_DQS_DP<5>")
		)
		(pad "251" smd rect
			(at 2.050034 31.874968 270)
			(size 0.519938 1.4986)
			(layers "F.Cu" "F.Mask" "F.Paste")
			(net "GND")
		)
		(pad "252" smd rect
			(at 2.050034 32.725106 270)
			(size 0.519938 1.4986)
			(layers "F.Cu" "F.Mask" "F.Paste")
			(net "M_B_CPU1_SB_DQ<6>")
		)
		(pad "253" smd rect
			(at 2.050034 33.57499 270)
			(size 0.519938 1.4986)
			(layers "F.Cu" "F.Mask" "F.Paste")
			(net "GND")
		)
		(pad "254" smd rect
			(at 2.050034 34.425128 270)
			(size 0.519938 1.4986)
			(layers "F.Cu" "F.Mask" "F.Paste")
			(net "M_B_CPU1_SB_DQ<7>")
		)
		(pad "255" smd rect
			(at 2.050034 35.275012 270)
			(size 0.519938 1.4986)
			(layers "F.Cu" "F.Mask" "F.Paste")
			(net "GND")
		)
		(pad "256" smd rect
			(at 2.050034 36.124896 270)
			(size 0.519938 1.4986)
			(layers "F.Cu" "F.Mask" "F.Paste")
			(net "M_B_CPU1_SB_DQ<10>")
		)
		(pad "257" smd rect
			(at 2.050034 36.975034 270)
			(size 0.519938 1.4986)
			(layers "F.Cu" "F.Mask" "F.Paste")
			(net "GND")
		)
		(pad "258" smd rect
			(at 2.050034 37.824918 270)
			(size 0.519938 1.4986)
			(layers "F.Cu" "F.Mask" "F.Paste")
			(net "M_B_CPU1_SB_DQ<11>")
		)
		(pad "259" smd rect
			(at 2.050034 38.675056 270)
			(size 0.519938 1.4986)
			(layers "F.Cu" "F.Mask" "F.Paste")
			(net "GND")
		)
		(pad "260" smd rect
			(at 2.050034 39.52494 270)
			(size 0.519938 1.4986)
			(layers "F.Cu" "F.Mask" "F.Paste")
			(net "M_B_CPU1_SB_DQS_DN<6>")
		)
		(pad "261" smd rect
			(at 2.050034 40.375078 270)
			(size 0.519938 1.4986)
			(layers "F.Cu" "F.Mask" "F.Paste")
			(net "M_B_CPU1_SB_DQS_DP<6>")
		)
		(pad "262" smd rect
			(at 2.050034 41.224962 270)
			(size 0.519938 1.4986)
			(layers "F.Cu" "F.Mask" "F.Paste")
			(net "GND")
		)
		(pad "263" smd rect
			(at 2.050034 42.0751 270)
			(size 0.519938 1.4986)
			(layers "F.Cu" "F.Mask" "F.Paste")
			(net "M_B_CPU1_SB_DQ<14>")
		)
		(pad "264" smd rect
			(at 2.050034 42.924984 270)
			(size 0.519938 1.4986)
			(layers "F.Cu" "F.Mask" "F.Paste")
			(net "GND")
		)
		(pad "265" smd rect
			(at 2.050034 43.775122 270)
			(size 0.519938 1.4986)
			(layers "F.Cu" "F.Mask" "F.Paste")
			(net "M_B_CPU1_SB_DQ<15>")
		)
		(pad "266" smd rect
			(at 2.050034 44.625006 270)
			(size 0.519938 1.4986)
			(layers "F.Cu" "F.Mask" "F.Paste")
			(net "GND")
		)
		(pad "267" smd rect
			(at 2.050034 45.47489 270)
			(size 0.519938 1.4986)
			(layers "F.Cu" "F.Mask" "F.Paste")
			(net "M_B_CPU1_SB_DQ<18>")
		)
		(pad "268" smd rect
			(at 2.050034 46.325028 270)
			(size 0.519938 1.4986)
			(layers "F.Cu" "F.Mask" "F.Paste")
			(net "GND")
		)
		(pad "269" smd rect
			(at 2.050034 47.174912 270)
			(size 0.519938 1.4986)
			(layers "F.Cu" "F.Mask" "F.Paste")
			(net "M_B_CPU1_SB_DQ<19>")
		)
		(pad "270" smd rect
			(at 2.050034 48.02505 270)
			(size 0.519938 1.4986)
			(layers "F.Cu" "F.Mask" "F.Paste")
			(net "GND")
		)
		(pad "271" smd rect
			(at 2.050034 48.874934 270)
			(size 0.519938 1.4986)
			(layers "F.Cu" "F.Mask" "F.Paste")
			(net "M_B_CPU1_SB_DQS_DN<7>")
		)
		(pad "272" smd rect
			(at 2.050034 49.725072 270)
			(size 0.519938 1.4986)
			(layers "F.Cu" "F.Mask" "F.Paste")
			(net "M_B_CPU1_SB_DQS_DP<7>")
		)
		(pad "273" smd rect
			(at 2.050034 50.574956 270)
			(size 0.519938 1.4986)
			(layers "F.Cu" "F.Mask" "F.Paste")
			(net "GND")
		)
		(pad "274" smd rect
			(at 2.050034 51.425094 270)
			(size 0.519938 1.4986)
			(layers "F.Cu" "F.Mask" "F.Paste")
			(net "M_B_CPU1_SB_DQ<22>")
		)
	)
)
